# T6G (Grand Teton) — schematic netlist excerpt (pin names and nets, part order shuffled) for the footprints in the layout excerpt that follows; sources: Cadence DE-HDL packaged netlist, KiCad conversion of 04192023_DAF0TMB3IC0_F0TG_MB_C_brd_V02_OCP.brd

PC327_1  Q_CAP  22UF 16V 20% X6S  pkg C0805  page 215 : A = SW_P12V_AUX_PVDDCR_SOC_P1_FLT ; B = GND
C6621  Q_CAP_DIFFBUS  DIFF BUS_0.22UF 6.3V 20% X6S  pkg C0201  page 308 : \1\ = P5E_CPU0_P3_TX_BUF_C_DP<12> ; \2\ = P5E_CPU0_P3_TX_BUF_DP<12>

DB14  TDR_3P  EMPTY  pkg TH2  page 260
  GND  = T1_GND
  IO1  = TDR_SE_45_OHM_IN6
  IO2  = TDR_SE_45_OHM_IN6

(kicad_pcb
	(version 20260206)
	(generator "pcbnew")
	(generator_version "10.0")
	(general
		(thickness 1.6)
		(legacy_teardrops no)
	)
	(paper "A4")
	(title_block
		(title "04192023_DAF0TMB3IC0_F0TG_MB_C_brd_V02_OCP.brd")
		(comment 1 "Grand Teton / footprints 7628-7630 of 8354")
	)
	(layers
		(0 "F.Cu" signal "TOP")
		(4 "In1.Cu" signal "GND")
		(6 "In2.Cu" signal "IN1")
		(8 "In3.Cu" signal "GND1")
		(10 "In4.Cu" signal "IN2")
		(12 "In5.Cu" signal "GND2")
		(14 "In6.Cu" signal "IN3")
		(16 "In7.Cu" signal "GND3")
		(18 "In8.Cu" signal "VCC")
		(20 "In9.Cu" signal "VCC1")
		(22 "In10.Cu" signal "GND4")
		(24 "In11.Cu" signal "IN4")
		(26 "In12.Cu" signal "GND5")
		(28 "In13.Cu" signal "IN5")
		(30 "In14.Cu" signal "GND6")
		(32 "In15.Cu" signal "IN6")
		(34 "In16.Cu" signal "GND7")
		(2 "B.Cu" signal "BOTTOM")
		(9 "F.Adhes" user "F.Adhesive")
		(11 "B.Adhes" user "B.Adhesive")
		(13 "F.Paste" user "Package Geometry/Pastemask Top")
		(15 "B.Paste" user "Package Geometry/Pastemask Bottom")
		(5 "F.SilkS" user "Ref Des/Silkscreen Top")
		(7 "B.SilkS" user "Ref Des/Silkscreen Bottom")
		(1 "F.Mask" user "Board Geometry/Soldermask Top")
		(3 "B.Mask" user "Board Geometry/Soldermask Bottom")
		(17 "Dwgs.User" user "User.Drawings")
		(19 "Cmts.User" user "User.Comments")
		(21 "Eco1.User" user "User.Eco1")
		(23 "Eco2.User" user "User.Eco2")
		(25 "Edge.Cuts" user "Board Geometry/Outline")
		(27 "Margin" user)
		(31 "F.CrtYd" user "Package Geometry/Place Bound Top")
		(29 "B.CrtYd" user "Package Geometry/Place Bound Bottom")
		(35 "F.Fab" user "Ref Des/Assembly Top")
		(33 "B.Fab" user "Ref Des/Assembly Bottom")
	)
	(footprint ""
		(layer "B.Cu")
		(at 114.439954 -168.142412 90)
		(property "Reference" "PC327_1"
			(at 0 0 90)
			(layer "B.SilkS")
			(hide yes)
			(effects
				(font
					(size 1.27 1.27)
				)
				(justify mirror)
			)
		)
		(property "Value" ""
			(at 0 0 90)
			(layer "B.Fab")
			(effects
				(font
					(size 1.27 1.27)
				)
				(justify mirror)
			)
		)
		(duplicate_pad_numbers_are_jumpers no)
		(fp_line
			(start 1.524 -0.762)
			(end -1.524 -0.762)
			(stroke
				(width 0.1524)
				(type default)
			)
			(layer "B.SilkS")
		)
		(fp_line
			(start -1.524 -0.762)
			(end -1.524 0.762)
			(stroke
				(width 0.1524)
				(type default)
			)
			(layer "B.SilkS")
		)
		(fp_line
			(start 1.524 0.762)
			(end 1.524 -0.762)
			(stroke
				(width 0.1524)
				(type default)
			)
			(layer "B.SilkS")
		)
		(fp_line
			(start -1.524 0.762)
			(end 1.524 0.762)
			(stroke
				(width 0.1524)
				(type default)
			)
			(layer "B.SilkS")
		)
		(fp_line
			(start 1.1049 -0.724916)
			(end 1.1049 0.724916)
			(stroke
				(width 0.1)
				(type default)
			)
			(layer "B.Fab")
		)
		(fp_line
			(start -1.1049 -0.724916)
			(end 1.1049 -0.724916)
			(stroke
				(width 0.1)
				(type default)
			)
			(layer "B.Fab")
		)
		(fp_line
			(start 1.1049 0.724916)
			(end -1.1049 0.724916)
			(stroke
				(width 0.1)
				(type default)
			)
			(layer "B.Fab")
		)
		(fp_line
			(start -1.1049 0.724916)
			(end -1.1049 -0.724916)
			(stroke
				(width 0.1)
				(type default)
			)
			(layer "B.Fab")
		)
		(pad "1" smd rect
			(at 0.889 0 90)
			(size 1.016 1.27)
			(layers "B.Cu" "B.Mask" "B.Paste")
			(net "SW_P12V_AUX_PVDDCR_SOC_P1_FLT")
		)
		(pad "2" smd rect
			(at -0.889 0 90)
			(size 1.016 1.27)
			(layers "B.Cu" "B.Mask" "B.Paste")
			(net "GND")
		)
	)
	(footprint ""
		(layer "B.Cu")
		(at 410.073602 -416.899344 90)
		(property "Reference" "C6621"
			(at 0 0 90)
			(layer "B.SilkS")
			(hide yes)
			(effects
				(font
					(size 1.27 1.27)
				)
				(justify mirror)
			)
		)
		(property "Value" ""
			(at 0 0 90)
			(layer "B.Fab")
			(effects
				(font
					(size 1.27 1.27)
				)
				(justify mirror)
			)
		)
		(duplicate_pad_numbers_are_jumpers no)
		(fp_line
			(start 0.299974 -0.150114)
			(end -0.299974 -0.150114)
			(stroke
				(width 0.1)
				(type default)
			)
			(layer "B.Fab")
		)
		(fp_line
			(start -0.299974 -0.150114)
			(end -0.299974 0.150114)
			(stroke
				(width 0.1)
				(type default)
			)
			(layer "B.Fab")
		)
		(fp_line
			(start 0.299974 0.150114)
			(end 0.299974 -0.150114)
			(stroke
				(width 0.1)
				(type default)
			)
			(layer "B.Fab")
		)
		(fp_line
			(start -0.299974 0.150114)
			(end 0.299974 0.150114)
			(stroke
				(width 0.1)
				(type default)
			)
			(layer "B.Fab")
		)
		(pad "1" smd rect
			(at 0.2667 0 270)
			(size 0.3048 0.381)
			(layers "B.Cu" "B.Mask" "B.Paste")
			(net "P5E_CPU0_P3_TX_BUF_C_DP<12>")
		)
		(pad "2" smd rect
			(at -0.2667 0 270)
			(size 0.3048 0.381)
			(layers "B.Cu" "B.Mask" "B.Paste")
			(net "P5E_CPU0_P3_TX_BUF_DP<12>")
		)
	)
	(footprint ""
		(layer "B.Cu")
		(at 474.29293 -212.746082)
		(property "Reference" "DB14"
			(at 2.639822 -5.63118 270)
			(unlocked yes)
			(layer "B.SilkS")
			(effects
				(font
					(size 0.7874 0.5842)
					(thickness 0.1524)
				)
				(justify left mirror)
			)
		)
		(property "Value" ""
			(at 0 0 0)
			(layer "B.Fab")
			(effects
				(font
					(size 1.27 1.27)
				)
				(justify mirror)
			)
		)
		(duplicate_pad_numbers_are_jumpers no)
		(fp_line
			(start -3.330702 -4.771136)
			(end 0 4.011168)
			(stroke
				(width 0.1524)
				(type default)
			)
			(layer "B.SilkS")
		)
		(fp_line
			(start 0 4.011168)
			(end 3.330702 -4.771136)
			(stroke
				(width 0.1524)
				(type default)
			)
			(layer "B.SilkS")
		)
		(fp_line
			(start 3.330702 -4.771136)
			(end -3.330702 -4.771136)
			(stroke
				(width 0.1524)
				(type default)
			)
			(layer "B.SilkS")
		)
		(fp_line
			(start -3.330702 -4.771136)
			(end 0 4.011168)
			(stroke
				(width 0.1)
				(type default)
			)
			(layer "B.Fab")
		)
		(fp_line
			(start 0 4.011168)
			(end 3.330702 -4.771136)
			(stroke
				(width 0.1)
				(type default)
			)
			(layer "B.Fab")
		)
		(fp_line
			(start 3.330702 -4.771136)
			(end -3.330702 -4.771136)
			(stroke
				(width 0.1)
				(type default)
			)
			(layer "B.Fab")
		)
		(pad "1" thru_hole circle
			(at 0 0 180)
			(size 2.159 2.159)
			(drill 1.7018)
			(layers "*.Cu" "*.Mask")
			(remove_unused_layers no)
			(net "T1_GND")
			(clearance 0.0254)
			(thermal_gap 0.0254)
		)
		(pad "2" thru_hole circle
			(at 1.27 -3.348736 180)
			(size 2.159 2.159)
			(drill 1.7018)
			(layers "*.Cu" "*.Mask")
			(remove_unused_layers no)
			(net "TDR_SE_45_OHM_IN6")
			(clearance 0.0254)
			(thermal_gap 0.0254)
		)
		(pad "3" thru_hole circle
			(at -1.27 -3.348736 180)
			(size 2.159 2.159)
			(drill 1.7018)
			(layers "*.Cu" "*.Mask")
			(remove_unused_layers no)
			(net "TDR_SE_45_OHM_IN6")
			(clearance 0.0254)
			(thermal_gap 0.0254)
		)
	)
)
